# BASEBOARD_FAB2 (Tioga Pass) — schematic netlist excerpt (pin names and nets, part order shuffled) for the footprints in the layout excerpt that follows; sources: Cadence DE-HDL packaged netlist, KiCad conversion of Wiwynn_Tioga_Pass_MB.brd

C6P18  CAPP  470UF 2.5V 20% ALUM  pkg 3018  page 203 : A = PVCCIN_CPU0 ; B = GND

Q1B1  MOSFET_N  BSZ019N03LS NFET  pkg LCC3  page 198
  SRC  = P12V_FAN
  GATE  = P12V_FAN_SWITCH_G
  DRN  = P12V_STBY

(kicad_pcb
	(version 20260206)
	(generator "pcbnew")
	(generator_version "10.0")
	(general
		(thickness 1.6)
		(legacy_teardrops no)
	)
	(paper "A4")
	(title_block
		(title "Wiwynn_Tioga_Pass_MB.brd")
		(comment 1 "Tioga Pass / footprints 3745-3746 of 4770")
	)
	(layers
		(0 "F.Cu" signal "TOP")
		(4 "In1.Cu" signal "L2GND")
		(6 "In2.Cu" signal "L3")
		(8 "In3.Cu" signal "L4GND")
		(10 "In4.Cu" signal "L5")
		(12 "In5.Cu" signal "L6GND")
		(14 "In6.Cu" signal "L7VCC")
		(16 "In7.Cu" signal "L8VCC")
		(18 "In8.Cu" signal "L9GND")
		(20 "In9.Cu" signal "L10")
		(22 "In10.Cu" signal "L11GND")
		(24 "In11.Cu" signal "L12")
		(26 "In12.Cu" signal "L13GND")
		(2 "B.Cu" signal "BOTTOM")
		(9 "F.Adhes" user "F.Adhesive")
		(11 "B.Adhes" user "B.Adhesive")
		(13 "F.Paste" user "Package Geometry/Pastemask Top")
		(15 "B.Paste" user "Package Geometry/Pastemask Bottom")
		(5 "F.SilkS" user "Ref Des/Silkscreen Top")
		(7 "B.SilkS" user "Ref Des/Silkscreen Bottom")
		(1 "F.Mask" user "Board Geometry/Soldermask Top")
		(3 "B.Mask" user "Board Geometry/Soldermask Bottom")
		(17 "Dwgs.User" user "User.Drawings")
		(19 "Cmts.User" user "User.Comments")
		(21 "Eco1.User" user "User.Eco1")
		(23 "Eco2.User" user "User.Eco2")
		(25 "Edge.Cuts" user "Board Geometry/Outline")
		(27 "Margin" user)
		(31 "F.CrtYd" user "Package Geometry/Place Bound Top")
		(29 "B.CrtYd" user "Package Geometry/Place Bound Bottom")
		(35 "F.Fab" user "Ref Des/Assembly Top")
		(33 "B.Fab" user "Ref Des/Assembly Bottom")
	)
	(footprint ""
		(layer "B.Cu")
		(at 210.847432 -73.279 -90)
		(property "Reference" "C6P18"
			(at -1.87833 -3.909568 0)
			(unlocked yes)
			(layer "B.SilkS")
			(effects
				(font
					(size 0.7874 0.5842)
					(thickness 0.1524)
				)
				(justify mirror)
			)
		)
		(property "Value" ""
			(at 0 0 90)
			(layer "B.Fab")
			(effects
				(font
					(size 1.27 1.27)
				)
				(justify mirror)
			)
		)
		(duplicate_pad_numbers_are_jumpers no)
		(fp_line
			(start -2.286 7.366)
			(end -1.600708 7.366)
			(stroke
				(width 0.1524)
				(type default)
			)
			(layer "B.SilkS")
		)
		(fp_line
			(start -2.286 7.366)
			(end -2.286 1.63195)
			(stroke
				(width 0.1524)
				(type default)
			)
			(layer "B.SilkS")
		)
		(fp_line
			(start 2.286 7.366)
			(end 1.60147 7.366)
			(stroke
				(width 0.1524)
				(type default)
			)
			(layer "B.SilkS")
		)
		(fp_line
			(start 2.286 7.366)
			(end 2.286 1.632712)
			(stroke
				(width 0.1524)
				(type default)
			)
			(layer "B.SilkS")
		)
		(fp_line
			(start -2.504948 1.633728)
			(end -1.6002 1.633728)
			(stroke
				(width 0.1524)
				(type default)
			)
			(layer "B.SilkS")
		)
		(fp_line
			(start 2.563114 1.633728)
			(end 1.6002 1.633728)
			(stroke
				(width 0.1524)
				(type default)
			)
			(layer "B.SilkS")
		)
		(fp_line
			(start -2.504948 -1.616456)
			(end -2.504948 1.633728)
			(stroke
				(width 0.1524)
				(type default)
			)
			(layer "B.SilkS")
		)
		(fp_line
			(start -1.6002 -1.616456)
			(end -2.504948 -1.616456)
			(stroke
				(width 0.1524)
				(type default)
			)
			(layer "B.SilkS")
		)
		(fp_line
			(start 1.6002 -1.616456)
			(end 2.563114 -1.616456)
			(stroke
				(width 0.1524)
				(type default)
			)
			(layer "B.SilkS")
		)
		(fp_line
			(start 2.563114 -1.616456)
			(end 2.563114 1.633728)
			(stroke
				(width 0.1524)
				(type default)
			)
			(layer "B.SilkS")
		)
		(fp_rect
			(start 2.286 7.366)
			(end -2.286 -0.254)
			(stroke
				(width 0)
				(type default)
			)
			(fill no)
			(layer "B.CrtYd")
		)
		(fp_line
			(start -2.286 7.366)
			(end 2.286 7.366)
			(stroke
				(width 0.1)
				(type default)
			)
			(layer "B.Fab")
		)
		(fp_line
			(start 2.286 7.366)
			(end 2.286 -0.254)
			(stroke
				(width 0.1)
				(type default)
			)
			(layer "B.Fab")
		)
		(fp_line
			(start -2.286 -0.254)
			(end -2.286 7.366)
			(stroke
				(width 0.1)
				(type default)
			)
			(layer "B.Fab")
		)
		(fp_line
			(start 2.286 -0.254)
			(end -2.286 -0.254)
			(stroke
				(width 0.1)
				(type default)
			)
			(layer "B.Fab")
		)
		(pad "1" smd rect
			(at 0 0 90)
			(size 2.54 3.048)
			(layers "B.Cu" "B.Mask" "B.Paste")
			(net "PVCCIN_CPU0")
		)
		(pad "2" smd rect
			(at 0 7.112 90)
			(size 2.54 3.048)
			(layers "B.Cu" "B.Mask" "B.Paste")
			(net "GND")
		)
	)
	(footprint ""
		(layer "B.Cu")
		(at 4.3942 -115.65382)
		(property "Reference" "Q1B1"
			(at -1.310894 -2.428748 180)
			(unlocked yes)
			(layer "B.SilkS")
			(effects
				(font
					(size 0.7874 0.5842)
					(thickness 0.1524)
				)
				(justify left mirror)
			)
		)
		(property "Value" ""
			(at 0 0 0)
			(layer "B.Fab")
			(effects
				(font
					(size 1.27 1.27)
				)
				(justify mirror)
			)
		)
		(duplicate_pad_numbers_are_jumpers no)
		(fp_line
			(start 0.245364 -1.379982)
			(end -3.15468 -1.379982)
			(stroke
				(width 0.1524)
				(type default)
			)
			(layer "B.SilkS")
		)
		(fp_line
			(start 0.245364 2.020062)
			(end -3.15468 2.020062)
			(stroke
				(width 0.1524)
				(type default)
			)
			(layer "B.SilkS")
		)
		(fp_circle
			(center 0.36703 -1.740408)
			(end 0.49403 -1.740408)
			(stroke
				(width 0.254)
				(type default)
			)
			(fill no)
			(layer "B.SilkS")
		)
		(fp_poly
			(pts
				(xy -0.890016 -0.82296) (xy -0.890016 1.46304) (xy -3.404616 1.46304) (xy -3.404616 1.13284) (xy -2.617216 1.13284)
				(xy -2.617216 0.811022) (xy -3.404616 0.811022) (xy -3.404616 0.480822) (xy -2.617216 0.480822)
				(xy -2.617216 0.159258) (xy -3.404616 0.159258) (xy -3.404616 -0.170942) (xy -2.617216 -0.170942)
				(xy -2.617216 -0.49276) (xy -3.404616 -0.49276) (xy -3.404616 -0.82296)
			)
			(stroke
				(width 0)
				(type default)
			)
			(fill yes)
			(layer "B.Paste")
		)
		(fp_poly
			(pts
				(xy 0.245364 -1.379982) (xy 0.245364 2.020062) (xy -3.15468 2.020062) (xy -3.15468 -1.379982)
			)
			(stroke
				(width 0)
				(type default)
			)
			(fill no)
			(layer "B.CrtYd")
		)
		(fp_line
			(start -3.15468 -1.379982)
			(end -3.15468 2.020062)
			(stroke
				(width 0.1)
				(type default)
			)
			(layer "B.Fab")
		)
		(fp_line
			(start -3.15468 2.020062)
			(end 0.245364 2.020062)
			(stroke
				(width 0.1)
				(type default)
			)
			(layer "B.Fab")
		)
		(fp_line
			(start 0.245364 -1.379982)
			(end -3.15468 -1.379982)
			(stroke
				(width 0.1)
				(type default)
			)
			(layer "B.Fab")
		)
		(fp_line
			(start 0.245364 2.020062)
			(end 0.245364 -1.379982)
			(stroke
				(width 0.1)
				(type default)
			)
			(layer "B.Fab")
		)
		(fp_circle
			(center 0.94996 -1.512316)
			(end 1.07696 -1.512316)
			(stroke
				(width 0.254)
				(type default)
			)
			(fill no)
			(layer "B.Fab")
		)
		(pad "1" smd custom
			(at 0 0 180)
			(size 0.24765 0.24765)
			(layers "B.Cu" "B.Mask" "B.Paste")
			(net "P12V_FAN")
			(options
				(clearance outline)
				(anchor circle)
			)
			(primitives
				(gr_poly
					(pts
						(xy 0.4953 -0.8255) (xy 0.4953 0.8255) (xy -0.4953 0.8255) (xy -0.4953 0.4953) (xy 0.0127 0.4953)
						(xy 0.0127 0.1651) (xy -0.4953 0.1651) (xy -0.4953 -0.1651) (xy 0.0127 -0.1651) (xy 0.0127 -0.4953)
						(xy -0.4953 -0.4953) (xy -0.4953 -0.8255)
					)
					(width 0)
					(fill yes)
				)
			)
		)
		(pad "4" smd rect
			(at 0 1.30048 180)
			(size 0.9906 0.3302)
			(layers "B.Cu" "B.Mask" "B.Paste")
			(net "P12V_FAN_SWITCH_G")
		)
		(pad "5" smd custom
			(at -2.147316 0.32004 180)
			(size 0.5715 0.5715)
			(layers "B.Cu" "B.Mask" "B.Paste")
			(net "P12V_STBY")
			(options
				(clearance outline)
				(anchor circle)
			)
			(primitives
				(gr_poly
					(pts
						(xy -1.2573 1.143) (xy -1.2573 -1.143) (xy 1.2573 -1.143) (xy 1.2573 -0.8128) (xy 0.4699 -0.8128)
						(xy 0.4699 -0.490982) (xy 1.2573 -0.490982) (xy 1.2573 -0.160782) (xy 0.4699 -0.160782) (xy 0.4699 0.160782)
						(xy 1.2573 0.160782) (xy 1.2573 0.490982) (xy 0.4699 0.490982) (xy 0.4699 0.8128) (xy 1.2573 0.8128)
						(xy 1.2573 1.143)
					)
					(width 0)
					(fill yes)
				)
			)
		)
	)
)
